(kicad_pcb
	(version 20260206)
	(generator "pcbnew")
	(generator_version "10.0")
	(general
		(thickness 1.6)
		(legacy_teardrops no)
	)
	(paper "A4")
	(title_block
		(title "01162023_DA0F0TEBIF0_F0T_Expander_BD_F_brd_V02_OCP.brd")
		(comment 1 "Grand Teton / footprints 3987-3993 of 9728")
	)
	(layers
		(0 "F.Cu" signal "TOP")
		(4 "In1.Cu" signal "GND")
		(6 "In2.Cu" signal "VCC")
		(8 "In3.Cu" signal "VCC1")
		(10 "In4.Cu" signal "GND1")
		(12 "In5.Cu" signal "IN1")
		(14 "In6.Cu" signal "GND2")
		(16 "In7.Cu" signal "IN2")
		(18 "In8.Cu" signal "GND3")
		(20 "In9.Cu" signal "IN3")
		(22 "In10.Cu" signal "GND4")
		(24 "In11.Cu" signal "IN4")
		(26 "In12.Cu" signal "GND5")
		(28 "In13.Cu" signal "IN5")
		(30 "In14.Cu" signal "GND6")
		(32 "In15.Cu" signal "IN6")
		(34 "In16.Cu" signal "GND7")
		(2 "B.Cu" signal "BOTTOM")
		(9 "F.Adhes" user "F.Adhesive")
		(11 "B.Adhes" user "B.Adhesive")
		(13 "F.Paste" user "Package Geometry/Pastemask Top")
		(15 "B.Paste" user "Package Geometry/Pastemask Bottom")
		(5 "F.SilkS" user "Ref Des/Silkscreen Top")
		(7 "B.SilkS" user "Ref Des/Silkscreen Bottom")
		(1 "F.Mask" user "Board Geometry/Soldermask Top")
		(3 "B.Mask" user "Board Geometry/Soldermask Bottom")
		(17 "Dwgs.User" user "User.Drawings")
		(19 "Cmts.User" user "User.Comments")
		(21 "Eco1.User" user "User.Eco1")
		(23 "Eco2.User" user "User.Eco2")
		(25 "Edge.Cuts" user "Board Geometry/Outline")
		(27 "Margin" user)
		(31 "F.CrtYd" user "Package Geometry/Place Bound Top")
		(29 "B.CrtYd" user "Package Geometry/Place Bound Bottom")
		(35 "F.Fab" user "Ref Des/Assembly Top")
		(33 "B.Fab" user "Ref Des/Assembly Bottom")
	)
	(footprint ""
		(layer "F.Cu")
		(at 348.477586 -255.82372 180)
		(property "Reference" "PC126"
			(at 0 0 180)
			(layer "F.SilkS")
			(hide yes)
			(effects
				(font
					(size 1.27 1.27)
				)
			)
		)
		(property "Value" ""
			(at 0 0 180)
			(layer "F.Fab")
			(effects
				(font
					(size 1.27 1.27)
				)
			)
		)
		(duplicate_pad_numbers_are_jumpers no)
		(fp_line
			(start 0.7874 0.4064)
			(end -0.7874 0.4064)
			(stroke
				(width 0.1524)
				(type default)
			)
			(layer "F.SilkS")
		)
		(fp_line
			(start 0.7874 -0.4064)
			(end 0.7874 0.4064)
			(stroke
				(width 0.1524)
				(type default)
			)
			(layer "F.SilkS")
		)
		(fp_line
			(start -0.7874 0.4064)
			(end -0.7874 -0.4064)
			(stroke
				(width 0.1524)
				(type default)
			)
			(layer "F.SilkS")
		)
		(fp_line
			(start -0.7874 -0.4064)
			(end 0.7874 -0.4064)
			(stroke
				(width 0.1524)
				(type default)
			)
			(layer "F.SilkS")
		)
		(fp_line
			(start 0.67945 0.3048)
			(end 0.120396 0.3048)
			(stroke
				(width 0.1)
				(type default)
			)
			(layer "F.Fab")
		)
		(fp_line
			(start 0.67945 -0.3048)
			(end 0.67945 0.3048)
			(stroke
				(width 0.1)
				(type default)
			)
			(layer "F.Fab")
		)
		(fp_line
			(start 0.12065 -0.2794)
			(end 0.12065 -0.3048)
			(stroke
				(width 0.1)
				(type default)
			)
			(layer "F.Fab")
		)
		(fp_line
			(start 0.12065 -0.3048)
			(end 0.67945 -0.3048)
			(stroke
				(width 0.1)
				(type default)
			)
			(layer "F.Fab")
		)
		(fp_line
			(start 0.120396 0.3048)
			(end 0.120396 0.2794)
			(stroke
				(width 0.1)
				(type default)
			)
			(layer "F.Fab")
		)
		(fp_line
			(start 0.120396 0.2794)
			(end -0.12065 0.2794)
			(stroke
				(width 0.1)
				(type default)
			)
			(layer "F.Fab")
		)
		(fp_line
			(start -0.12065 0.3048)
			(end -0.67945 0.3048)
			(stroke
				(width 0.1)
				(type default)
			)
			(layer "F.Fab")
		)
		(fp_line
			(start -0.12065 0.2794)
			(end -0.12065 0.3048)
			(stroke
				(width 0.1)
				(type default)
			)
			(layer "F.Fab")
		)
		(fp_line
			(start -0.12065 -0.2794)
			(end 0.12065 -0.2794)
			(stroke
				(width 0.1)
				(type default)
			)
			(layer "F.Fab")
		)
		(fp_line
			(start -0.12065 -0.305054)
			(end -0.12065 -0.2794)
			(stroke
				(width 0.1)
				(type default)
			)
			(layer "F.Fab")
		)
		(fp_line
			(start -0.67945 0.3048)
			(end -0.67945 -0.305054)
			(stroke
				(width 0.1)
				(type default)
			)
			(layer "F.Fab")
		)
		(fp_line
			(start -0.67945 -0.305054)
			(end -0.12065 -0.305054)
			(stroke
				(width 0.1)
				(type default)
			)
			(layer "F.Fab")
		)
		(pad "1" smd circle
			(at -0.40005 0 180)
			(size 0 0)
			(layers "F.Cu" "F.Mask" "F.Paste")
			(net "P0V8_PEX2_VDD")
		)
		(pad "2" smd circle
			(at 0.40005 0 180)
			(size 0 0)
			(layers "F.Cu" "F.Mask" "F.Paste")
			(net "GND")
		)
	)
	(footprint ""
		(layer "F.Cu")
		(at 323.917818 -219.579698 180)
		(property "Reference" "R2983"
			(at 0 0 180)
			(layer "F.SilkS")
			(hide yes)
			(effects
				(font
					(size 1.27 1.27)
				)
			)
		)
		(property "Value" ""
			(at 0 0 180)
			(layer "F.Fab")
			(effects
				(font
					(size 1.27 1.27)
				)
			)
		)
		(duplicate_pad_numbers_are_jumpers no)
		(fp_line
			(start 0.7874 0.4064)
			(end -0.7874 0.4064)
			(stroke
				(width 0.1524)
				(type default)
			)
			(layer "F.SilkS")
		)
		(fp_line
			(start 0.7874 -0.4064)
			(end 0.7874 0.4064)
			(stroke
				(width 0.1524)
				(type default)
			)
			(layer "F.SilkS")
		)
		(fp_line
			(start -0.7874 0.4064)
			(end -0.7874 -0.4064)
			(stroke
				(width 0.1524)
				(type default)
			)
			(layer "F.SilkS")
		)
		(fp_line
			(start -0.7874 -0.4064)
			(end 0.7874 -0.4064)
			(stroke
				(width 0.1524)
				(type default)
			)
			(layer "F.SilkS")
		)
		(fp_line
			(start 0.67945 0.3048)
			(end 0.120396 0.3048)
			(stroke
				(width 0.1)
				(type default)
			)
			(layer "F.Fab")
		)
		(fp_line
			(start 0.67945 -0.3048)
			(end 0.67945 0.3048)
			(stroke
				(width 0.1)
				(type default)
			)
			(layer "F.Fab")
		)
		(fp_line
			(start 0.12065 -0.2794)
			(end 0.12065 -0.3048)
			(stroke
				(width 0.1)
				(type default)
			)
			(layer "F.Fab")
		)
		(fp_line
			(start 0.12065 -0.3048)
			(end 0.67945 -0.3048)
			(stroke
				(width 0.1)
				(type default)
			)
			(layer "F.Fab")
		)
		(fp_line
			(start 0.120396 0.3048)
			(end 0.120396 0.2794)
			(stroke
				(width 0.1)
				(type default)
			)
			(layer "F.Fab")
		)
		(fp_line
			(start 0.120396 0.2794)
			(end -0.12065 0.2794)
			(stroke
				(width 0.1)
				(type default)
			)
			(layer "F.Fab")
		)
		(fp_line
			(start -0.12065 0.3048)
			(end -0.67945 0.3048)
			(stroke
				(width 0.1)
				(type default)
			)
			(layer "F.Fab")
		)
		(fp_line
			(start -0.12065 0.2794)
			(end -0.12065 0.3048)
			(stroke
				(width 0.1)
				(type default)
			)
			(layer "F.Fab")
		)
		(fp_line
			(start -0.12065 -0.2794)
			(end 0.12065 -0.2794)
			(stroke
				(width 0.1)
				(type default)
			)
			(layer "F.Fab")
		)
		(fp_line
			(start -0.12065 -0.305054)
			(end -0.12065 -0.2794)
			(stroke
				(width 0.1)
				(type default)
			)
			(layer "F.Fab")
		)
		(fp_line
			(start -0.67945 0.3048)
			(end -0.67945 -0.305054)
			(stroke
				(width 0.1)
				(type default)
			)
			(layer "F.Fab")
		)
		(fp_line
			(start -0.67945 -0.305054)
			(end -0.12065 -0.305054)
			(stroke
				(width 0.1)
				(type default)
			)
			(layer "F.Fab")
		)
		(pad "1" smd circle
			(at -0.40005 0 180)
			(size 0 0)
			(layers "F.Cu" "F.Mask" "F.Paste")
			(net "LED_POSTCODE_5")
		)
		(pad "2" smd circle
			(at 0.40005 0 180)
			(size 0 0)
			(layers "F.Cu" "F.Mask" "F.Paste")
			(net "LED_POSTCODE_R_5")
		)
	)
	(footprint ""
		(layer "F.Cu")
		(at 154.707844 -158.3944 180)
		(property "Reference" "R113"
			(at 0 0 180)
			(layer "F.SilkS")
			(hide yes)
			(effects
				(font
					(size 1.27 1.27)
				)
			)
		)
		(property "Value" ""
			(at 0 0 180)
			(layer "F.Fab")
			(effects
				(font
					(size 1.27 1.27)
				)
			)
		)
		(duplicate_pad_numbers_are_jumpers no)
		(fp_line
			(start 0.7874 0.4064)
			(end -0.7874 0.4064)
			(stroke
				(width 0.1524)
				(type default)
			)
			(layer "F.SilkS")
		)
		(fp_line
			(start 0.7874 -0.4064)
			(end 0.7874 0.4064)
			(stroke
				(width 0.1524)
				(type default)
			)
			(layer "F.SilkS")
		)
		(fp_line
			(start -0.7874 0.4064)
			(end -0.7874 -0.4064)
			(stroke
				(width 0.1524)
				(type default)
			)
			(layer "F.SilkS")
		)
		(fp_line
			(start -0.7874 -0.4064)
			(end 0.7874 -0.4064)
			(stroke
				(width 0.1524)
				(type default)
			)
			(layer "F.SilkS")
		)
		(fp_line
			(start 0.67945 0.3048)
			(end 0.120396 0.3048)
			(stroke
				(width 0.1)
				(type default)
			)
			(layer "F.Fab")
		)
		(fp_line
			(start 0.67945 -0.3048)
			(end 0.67945 0.3048)
			(stroke
				(width 0.1)
				(type default)
			)
			(layer "F.Fab")
		)
		(fp_line
			(start 0.12065 -0.2794)
			(end 0.12065 -0.3048)
			(stroke
				(width 0.1)
				(type default)
			)
			(layer "F.Fab")
		)
		(fp_line
			(start 0.12065 -0.3048)
			(end 0.67945 -0.3048)
			(stroke
				(width 0.1)
				(type default)
			)
			(layer "F.Fab")
		)
		(fp_line
			(start 0.120396 0.3048)
			(end 0.120396 0.2794)
			(stroke
				(width 0.1)
				(type default)
			)
			(layer "F.Fab")
		)
		(fp_line
			(start 0.120396 0.2794)
			(end -0.12065 0.2794)
			(stroke
				(width 0.1)
				(type default)
			)
			(layer "F.Fab")
		)
		(fp_line
			(start -0.12065 0.3048)
			(end -0.67945 0.3048)
			(stroke
				(width 0.1)
				(type default)
			)
			(layer "F.Fab")
		)
		(fp_line
			(start -0.12065 0.2794)
			(end -0.12065 0.3048)
			(stroke
				(width 0.1)
				(type default)
			)
			(layer "F.Fab")
		)
		(fp_line
			(start -0.12065 -0.2794)
			(end 0.12065 -0.2794)
			(stroke
				(width 0.1)
				(type default)
			)
			(layer "F.Fab")
		)
		(fp_line
			(start -0.12065 -0.305054)
			(end -0.12065 -0.2794)
			(stroke
				(width 0.1)
				(type default)
			)
			(layer "F.Fab")
		)
		(fp_line
			(start -0.67945 0.3048)
			(end -0.67945 -0.305054)
			(stroke
				(width 0.1)
				(type default)
			)
			(layer "F.Fab")
		)
		(fp_line
			(start -0.67945 -0.305054)
			(end -0.12065 -0.305054)
			(stroke
				(width 0.1)
				(type default)
			)
			(layer "F.Fab")
		)
		(pad "1" smd circle
			(at -0.40005 0 180)
			(size 0 0)
			(layers "F.Cu" "F.Mask" "F.Paste")
			(net "NIC2_LD_N")
		)
		(pad "2" smd circle
			(at 0.40005 0 180)
			(size 0 0)
			(layers "F.Cu" "F.Mask" "F.Paste")
			(net "P3V3_NIC2")
		)
	)
	(footprint ""
		(layer "F.Cu")
		(at 304.634392 -34.546286 180)
		(property "Reference" "C503"
			(at 0 0 180)
			(layer "F.SilkS")
			(hide yes)
			(effects
				(font
					(size 1.27 1.27)
				)
			)
		)
		(property "Value" ""
			(at 0 0 180)
			(layer "F.Fab")
			(effects
				(font
					(size 1.27 1.27)
				)
			)
		)
		(duplicate_pad_numbers_are_jumpers no)
		(fp_line
			(start 0.299974 0.150114)
			(end -0.299974 0.150114)
			(stroke
				(width 0.1)
				(type default)
			)
			(layer "F.Fab")
		)
		(fp_line
			(start 0.299974 -0.150114)
			(end 0.299974 0.150114)
			(stroke
				(width 0.1)
				(type default)
			)
			(layer "F.Fab")
		)
		(fp_line
			(start -0.299974 0.150114)
			(end -0.299974 -0.150114)
			(stroke
				(width 0.1)
				(type default)
			)
			(layer "F.Fab")
		)
		(fp_line
			(start -0.299974 -0.150114)
			(end 0.299974 -0.150114)
			(stroke
				(width 0.1)
				(type default)
			)
			(layer "F.Fab")
		)
		(pad "1" smd rect
			(at -0.2667 0 180)
			(size 0.3048 0.381)
			(layers "F.Cu" "F.Mask" "F.Paste")
			(net "P5E_PEX2_STN2_TX_DP<39>")
		)
		(pad "2" smd rect
			(at 0.2667 0 180)
			(size 0.3048 0.381)
			(layers "F.Cu" "F.Mask" "F.Paste")
			(net "P5E_PEX2_STN2_TX_C_DP<39>")
		)
	)
	(footprint ""
		(layer "F.Cu")
		(at 382.511046 -61.386974)
		(property "Reference" "R4503"
			(at 0 0 0)
			(layer "F.SilkS")
			(hide yes)
			(effects
				(font
					(size 1.27 1.27)
				)
			)
		)
		(property "Value" ""
			(at 0 0 0)
			(layer "F.Fab")
			(effects
				(font
					(size 1.27 1.27)
				)
			)
		)
		(duplicate_pad_numbers_are_jumpers no)
		(fp_line
			(start -0.7874 -0.4064)
			(end 0.7874 -0.4064)
			(stroke
				(width 0.1524)
				(type default)
			)
			(layer "F.SilkS")
		)
		(fp_line
			(start -0.7874 0.4064)
			(end -0.7874 -0.4064)
			(stroke
				(width 0.1524)
				(type default)
			)
			(layer "F.SilkS")
		)
		(fp_line
			(start 0.7874 -0.4064)
			(end 0.7874 0.4064)
			(stroke
				(width 0.1524)
				(type default)
			)
			(layer "F.SilkS")
		)
		(fp_line
			(start 0.7874 0.4064)
			(end -0.7874 0.4064)
			(stroke
				(width 0.1524)
				(type default)
			)
			(layer "F.SilkS")
		)
		(fp_line
			(start -0.67945 -0.305054)
			(end -0.12065 -0.305054)
			(stroke
				(width 0.1)
				(type default)
			)
			(layer "F.Fab")
		)
		(fp_line
			(start -0.67945 0.3048)
			(end -0.67945 -0.305054)
			(stroke
				(width 0.1)
				(type default)
			)
			(layer "F.Fab")
		)
		(fp_line
			(start -0.12065 -0.305054)
			(end -0.12065 -0.2794)
			(stroke
				(width 0.1)
				(type default)
			)
			(layer "F.Fab")
		)
		(fp_line
			(start -0.12065 -0.2794)
			(end 0.12065 -0.2794)
			(stroke
				(width 0.1)
				(type default)
			)
			(layer "F.Fab")
		)
		(fp_line
			(start -0.12065 0.2794)
			(end -0.12065 0.3048)
			(stroke
				(width 0.1)
				(type default)
			)
			(layer "F.Fab")
		)
		(fp_line
			(start -0.12065 0.3048)
			(end -0.67945 0.3048)
			(stroke
				(width 0.1)
				(type default)
			)
			(layer "F.Fab")
		)
		(fp_line
			(start 0.120396 0.2794)
			(end -0.12065 0.2794)
			(stroke
				(width 0.1)
				(type default)
			)
			(layer "F.Fab")
		)
		(fp_line
			(start 0.120396 0.3048)
			(end 0.120396 0.2794)
			(stroke
				(width 0.1)
				(type default)
			)
			(layer "F.Fab")
		)
		(fp_line
			(start 0.12065 -0.3048)
			(end 0.67945 -0.3048)
			(stroke
				(width 0.1)
				(type default)
			)
			(layer "F.Fab")
		)
		(fp_line
			(start 0.12065 -0.2794)
			(end 0.12065 -0.3048)
			(stroke
				(width 0.1)
				(type default)
			)
			(layer "F.Fab")
		)
		(fp_line
			(start 0.67945 -0.3048)
			(end 0.67945 0.3048)
			(stroke
				(width 0.1)
				(type default)
			)
			(layer "F.Fab")
		)
		(fp_line
			(start 0.67945 0.3048)
			(end 0.120396 0.3048)
			(stroke
				(width 0.1)
				(type default)
			)
			(layer "F.Fab")
		)
		(pad "1" smd circle
			(at -0.40005 0)
			(size 0 0)
			(layers "F.Cu" "F.Mask" "F.Paste")
			(net "PWRGD_P3V3_SSD13")
		)
		(pad "2" smd circle
			(at 0.40005 0)
			(size 0 0)
			(layers "F.Cu" "F.Mask" "F.Paste")
			(net "PWRGD_P3V3_SSD13_R")
		)
	)
	(footprint ""
		(layer "F.Cu")
		(at 147.047458 -36.686998 90)
		(property "Reference" "C3662"
			(at 0 0 90)
			(layer "F.SilkS")
			(hide yes)
			(effects
				(font
					(size 1.27 1.27)
				)
			)
		)
		(property "Value" ""
			(at 0 0 90)
			(layer "F.Fab")
			(effects
				(font
					(size 1.27 1.27)
				)
			)
		)
		(duplicate_pad_numbers_are_jumpers no)
		(fp_line
			(start 0.7874 -0.4064)
			(end 0.7874 0.4064)
			(stroke
				(width 0.1524)
				(type default)
			)
			(layer "F.SilkS")
		)
		(fp_line
			(start -0.7874 -0.4064)
			(end 0.7874 -0.4064)
			(stroke
				(width 0.1524)
				(type default)
			)
			(layer "F.SilkS")
		)
		(fp_line
			(start 0.7874 0.4064)
			(end -0.7874 0.4064)
			(stroke
				(width 0.1524)
				(type default)
			)
			(layer "F.SilkS")
		)
		(fp_line
			(start -0.7874 0.4064)
			(end -0.7874 -0.4064)
			(stroke
				(width 0.1524)
				(type default)
			)
			(layer "F.SilkS")
		)
		(fp_line
			(start -0.12065 -0.305054)
			(end -0.12065 -0.2794)
			(stroke
				(width 0.1)
				(type default)
			)
			(layer "F.Fab")
		)
		(fp_line
			(start -0.67945 -0.305054)
			(end -0.12065 -0.305054)
			(stroke
				(width 0.1)
				(type default)
			)
			(layer "F.Fab")
		)
		(fp_line
			(start 0.67945 -0.3048)
			(end 0.67945 0.3048)
			(stroke
				(width 0.1)
				(type default)
			)
			(layer "F.Fab")
		)
		(fp_line
			(start 0.12065 -0.3048)
			(end 0.67945 -0.3048)
			(stroke
				(width 0.1)
				(type default)
			)
			(layer "F.Fab")
		)
		(fp_line
			(start 0.12065 -0.2794)
			(end 0.12065 -0.3048)
			(stroke
				(width 0.1)
				(type default)
			)
			(layer "F.Fab")
		)
		(fp_line
			(start -0.12065 -0.2794)
			(end 0.12065 -0.2794)
			(stroke
				(width 0.1)
				(type default)
			)
			(layer "F.Fab")
		)
		(fp_line
			(start 0.120396 0.2794)
			(end -0.12065 0.2794)
			(stroke
				(width 0.1)
				(type default)
			)
			(layer "F.Fab")
		)
		(fp_line
			(start -0.12065 0.2794)
			(end -0.12065 0.3048)
			(stroke
				(width 0.1)
				(type default)
			)
			(layer "F.Fab")
		)
		(fp_line
			(start 0.67945 0.3048)
			(end 0.120396 0.3048)
			(stroke
				(width 0.1)
				(type default)
			)
			(layer "F.Fab")
		)
		(fp_line
			(start 0.120396 0.3048)
			(end 0.120396 0.2794)
			(stroke
				(width 0.1)
				(type default)
			)
			(layer "F.Fab")
		)
		(fp_line
			(start -0.12065 0.3048)
			(end -0.67945 0.3048)
			(stroke
				(width 0.1)
				(type default)
			)
			(layer "F.Fab")
		)
		(fp_line
			(start -0.67945 0.3048)
			(end -0.67945 -0.305054)
			(stroke
				(width 0.1)
				(type default)
			)
			(layer "F.Fab")
		)
		(pad "1" smd circle
			(at -0.40005 0 90)
			(size 0 0)
			(layers "F.Cu" "F.Mask" "F.Paste")
			(net "P3V3_AUX")
		)
		(pad "2" smd circle
			(at 0.40005 0 90)
			(size 0 0)
			(layers "F.Cu" "F.Mask" "F.Paste")
			(net "GND")
		)
	)
	(footprint ""
		(layer "F.Cu")
		(at 193.162428 -22.955504 -90)
		(property "Reference" "C2723"
			(at 0 0 270)
			(layer "F.SilkS")
			(hide yes)
			(effects
				(font
					(size 1.27 1.27)
				)
			)
		)
		(property "Value" ""
			(at 0 0 270)
			(layer "F.Fab")
			(effects
				(font
					(size 1.27 1.27)
				)
			)
		)
		(duplicate_pad_numbers_are_jumpers no)
		(fp_line
			(start -0.7874 0.4064)
			(end -0.7874 -0.4064)
			(stroke
				(width 0.1524)
				(type default)
			)
			(layer "F.SilkS")
		)
		(fp_line
			(start 0.7874 0.4064)
			(end -0.7874 0.4064)
			(stroke
				(width 0.1524)
				(type default)
			)
			(layer "F.SilkS")
		)
		(fp_line
			(start -0.7874 -0.4064)
			(end 0.7874 -0.4064)
			(stroke
				(width 0.1524)
				(type default)
			)
			(layer "F.SilkS")
		)
		(fp_line
			(start 0.7874 -0.4064)
			(end 0.7874 0.4064)
			(stroke
				(width 0.1524)
				(type default)
			)
			(layer "F.SilkS")
		)
		(fp_line
			(start -0.67945 0.3048)
			(end -0.67945 -0.305054)
			(stroke
				(width 0.1)
				(type default)
			)
			(layer "F.Fab")
		)
		(fp_line
			(start -0.12065 0.3048)
			(end -0.67945 0.3048)
			(stroke
				(width 0.1)
				(type default)
			)
			(layer "F.Fab")
		)
		(fp_line
			(start 0.120396 0.3048)
			(end 0.120396 0.2794)
			(stroke
				(width 0.1)
				(type default)
			)
			(layer "F.Fab")
		)
		(fp_line
			(start 0.67945 0.3048)
			(end 0.120396 0.3048)
			(stroke
				(width 0.1)
				(type default)
			)
			(layer "F.Fab")
		)
		(fp_line
			(start -0.12065 0.2794)
			(end -0.12065 0.3048)
			(stroke
				(width 0.1)
				(type default)
			)
			(layer "F.Fab")
		)
		(fp_line
			(start 0.120396 0.2794)
			(end -0.12065 0.2794)
			(stroke
				(width 0.1)
				(type default)
			)
			(layer "F.Fab")
		)
		(fp_line
			(start -0.12065 -0.2794)
			(end 0.12065 -0.2794)
			(stroke
				(width 0.1)
				(type default)
			)
			(layer "F.Fab")
		)
		(fp_line
			(start 0.12065 -0.2794)
			(end 0.12065 -0.3048)
			(stroke
				(width 0.1)
				(type default)
			)
			(layer "F.Fab")
		)
		(fp_line
			(start 0.12065 -0.3048)
			(end 0.67945 -0.3048)
			(stroke
				(width 0.1)
				(type default)
			)
			(layer "F.Fab")
		)
		(fp_line
			(start 0.67945 -0.3048)
			(end 0.67945 0.3048)
			(stroke
				(width 0.1)
				(type default)
			)
			(layer "F.Fab")
		)
		(fp_line
			(start -0.67945 -0.305054)
			(end -0.12065 -0.305054)
			(stroke
				(width 0.1)
				(type default)
			)
			(layer "F.Fab")
		)
		(fp_line
			(start -0.12065 -0.305054)
			(end -0.12065 -0.2794)
			(stroke
				(width 0.1)
				(type default)
			)
			(layer "F.Fab")
		)
		(pad "1" smd circle
			(at -0.40005 0 270)
			(size 0 0)
			(layers "F.Cu" "F.Mask" "F.Paste")
			(net "GND")
		)
		(pad "2" smd circle
			(at 0.40005 0 270)
			(size 0 0)
			(layers "F.Cu" "F.Mask" "F.Paste")
			(net "P3V3_AUX")
		)
	)
)
